(kicad_pcb
	(version 20260206)
	(generator "pcbnew")
	(generator_version "10.0")
	(general
		(thickness 1.6)
		(legacy_teardrops no)
	)
	(paper "A4")
	(title_block
		(title "01162023_DA0F0TEBIF0_F0T_Expander_BD_F_brd_V02_OCP.brd")
		(comment 1 "Grand Teton / footprints 5267-5272 of 9728")
	)
	(layers
		(0 "F.Cu" signal "TOP")
		(4 "In1.Cu" signal "GND")
		(6 "In2.Cu" signal "VCC")
		(8 "In3.Cu" signal "VCC1")
		(10 "In4.Cu" signal "GND1")
		(12 "In5.Cu" signal "IN1")
		(14 "In6.Cu" signal "GND2")
		(16 "In7.Cu" signal "IN2")
		(18 "In8.Cu" signal "GND3")
		(20 "In9.Cu" signal "IN3")
		(22 "In10.Cu" signal "GND4")
		(24 "In11.Cu" signal "IN4")
		(26 "In12.Cu" signal "GND5")
		(28 "In13.Cu" signal "IN5")
		(30 "In14.Cu" signal "GND6")
		(32 "In15.Cu" signal "IN6")
		(34 "In16.Cu" signal "GND7")
		(2 "B.Cu" signal "BOTTOM")
		(9 "F.Adhes" user "F.Adhesive")
		(11 "B.Adhes" user "B.Adhesive")
		(13 "F.Paste" user "Package Geometry/Pastemask Top")
		(15 "B.Paste" user "Package Geometry/Pastemask Bottom")
		(5 "F.SilkS" user "Ref Des/Silkscreen Top")
		(7 "B.SilkS" user "Ref Des/Silkscreen Bottom")
		(1 "F.Mask" user "Board Geometry/Soldermask Top")
		(3 "B.Mask" user "Board Geometry/Soldermask Bottom")
		(17 "Dwgs.User" user "User.Drawings")
		(19 "Cmts.User" user "User.Comments")
		(21 "Eco1.User" user "User.Eco1")
		(23 "Eco2.User" user "User.Eco2")
		(25 "Edge.Cuts" user "Board Geometry/Outline")
		(27 "Margin" user)
		(31 "F.CrtYd" user "Package Geometry/Place Bound Top")
		(29 "B.CrtYd" user "Package Geometry/Place Bound Bottom")
		(35 "F.Fab" user "Ref Des/Assembly Top")
		(33 "B.Fab" user "Ref Des/Assembly Bottom")
	)
	(footprint ""
		(layer "F.Cu")
		(at 75.66787 -18.437098)
		(property "Reference" "R1651"
			(at 0 0 0)
			(layer "F.SilkS")
			(hide yes)
			(effects
				(font
					(size 1.27 1.27)
				)
			)
		)
		(property "Value" ""
			(at 0 0 0)
			(layer "F.Fab")
			(effects
				(font
					(size 1.27 1.27)
				)
			)
		)
		(duplicate_pad_numbers_are_jumpers no)
		(fp_line
			(start -0.7874 -0.4064)
			(end 0.7874 -0.4064)
			(stroke
				(width 0.1524)
				(type default)
			)
			(layer "F.SilkS")
		)
		(fp_line
			(start -0.7874 0.4064)
			(end -0.7874 -0.4064)
			(stroke
				(width 0.1524)
				(type default)
			)
			(layer "F.SilkS")
		)
		(fp_line
			(start 0.7874 -0.4064)
			(end 0.7874 0.4064)
			(stroke
				(width 0.1524)
				(type default)
			)
			(layer "F.SilkS")
		)
		(fp_line
			(start 0.7874 0.4064)
			(end -0.7874 0.4064)
			(stroke
				(width 0.1524)
				(type default)
			)
			(layer "F.SilkS")
		)
		(fp_line
			(start -0.67945 -0.305054)
			(end -0.12065 -0.305054)
			(stroke
				(width 0.1)
				(type default)
			)
			(layer "F.Fab")
		)
		(fp_line
			(start -0.67945 0.3048)
			(end -0.67945 -0.305054)
			(stroke
				(width 0.1)
				(type default)
			)
			(layer "F.Fab")
		)
		(fp_line
			(start -0.12065 -0.305054)
			(end -0.12065 -0.2794)
			(stroke
				(width 0.1)
				(type default)
			)
			(layer "F.Fab")
		)
		(fp_line
			(start -0.12065 -0.2794)
			(end 0.12065 -0.2794)
			(stroke
				(width 0.1)
				(type default)
			)
			(layer "F.Fab")
		)
		(fp_line
			(start -0.12065 0.2794)
			(end -0.12065 0.3048)
			(stroke
				(width 0.1)
				(type default)
			)
			(layer "F.Fab")
		)
		(fp_line
			(start -0.12065 0.3048)
			(end -0.67945 0.3048)
			(stroke
				(width 0.1)
				(type default)
			)
			(layer "F.Fab")
		)
		(fp_line
			(start 0.120396 0.2794)
			(end -0.12065 0.2794)
			(stroke
				(width 0.1)
				(type default)
			)
			(layer "F.Fab")
		)
		(fp_line
			(start 0.120396 0.3048)
			(end 0.120396 0.2794)
			(stroke
				(width 0.1)
				(type default)
			)
			(layer "F.Fab")
		)
		(fp_line
			(start 0.12065 -0.3048)
			(end 0.67945 -0.3048)
			(stroke
				(width 0.1)
				(type default)
			)
			(layer "F.Fab")
		)
		(fp_line
			(start 0.12065 -0.2794)
			(end 0.12065 -0.3048)
			(stroke
				(width 0.1)
				(type default)
			)
			(layer "F.Fab")
		)
		(fp_line
			(start 0.67945 -0.3048)
			(end 0.67945 0.3048)
			(stroke
				(width 0.1)
				(type default)
			)
			(layer "F.Fab")
		)
		(fp_line
			(start 0.67945 0.3048)
			(end 0.120396 0.3048)
			(stroke
				(width 0.1)
				(type default)
			)
			(layer "F.Fab")
		)
		(pad "1" smd circle
			(at -0.40005 0)
			(size 0 0)
			(layers "F.Cu" "F.Mask" "F.Paste")
			(net "SMB_ISO_SSD2_R_SCL")
		)
		(pad "2" smd circle
			(at 0.40005 0)
			(size 0 0)
			(layers "F.Cu" "F.Mask" "F.Paste")
			(net "SMB_ISO_SSD2_SCL")
		)
	)
	(footprint ""
		(layer "F.Cu")
		(at 240.24971 -158.828994 180)
		(property "Reference" "R5966"
			(at 0 0 180)
			(layer "F.SilkS")
			(hide yes)
			(effects
				(font
					(size 1.27 1.27)
				)
			)
		)
		(property "Value" ""
			(at 0 0 180)
			(layer "F.Fab")
			(effects
				(font
					(size 1.27 1.27)
				)
			)
		)
		(duplicate_pad_numbers_are_jumpers no)
		(fp_line
			(start 0.7874 0.4064)
			(end -0.7874 0.4064)
			(stroke
				(width 0.1524)
				(type default)
			)
			(layer "F.SilkS")
		)
		(fp_line
			(start 0.7874 -0.4064)
			(end 0.7874 0.4064)
			(stroke
				(width 0.1524)
				(type default)
			)
			(layer "F.SilkS")
		)
		(fp_line
			(start -0.7874 0.4064)
			(end -0.7874 -0.4064)
			(stroke
				(width 0.1524)
				(type default)
			)
			(layer "F.SilkS")
		)
		(fp_line
			(start -0.7874 -0.4064)
			(end 0.7874 -0.4064)
			(stroke
				(width 0.1524)
				(type default)
			)
			(layer "F.SilkS")
		)
		(fp_line
			(start 0.67945 0.3048)
			(end 0.120396 0.3048)
			(stroke
				(width 0.1)
				(type default)
			)
			(layer "F.Fab")
		)
		(fp_line
			(start 0.67945 -0.3048)
			(end 0.67945 0.3048)
			(stroke
				(width 0.1)
				(type default)
			)
			(layer "F.Fab")
		)
		(fp_line
			(start 0.12065 -0.2794)
			(end 0.12065 -0.3048)
			(stroke
				(width 0.1)
				(type default)
			)
			(layer "F.Fab")
		)
		(fp_line
			(start 0.12065 -0.3048)
			(end 0.67945 -0.3048)
			(stroke
				(width 0.1)
				(type default)
			)
			(layer "F.Fab")
		)
		(fp_line
			(start 0.120396 0.3048)
			(end 0.120396 0.2794)
			(stroke
				(width 0.1)
				(type default)
			)
			(layer "F.Fab")
		)
		(fp_line
			(start 0.120396 0.2794)
			(end -0.12065 0.2794)
			(stroke
				(width 0.1)
				(type default)
			)
			(layer "F.Fab")
		)
		(fp_line
			(start -0.12065 0.3048)
			(end -0.67945 0.3048)
			(stroke
				(width 0.1)
				(type default)
			)
			(layer "F.Fab")
		)
		(fp_line
			(start -0.12065 0.2794)
			(end -0.12065 0.3048)
			(stroke
				(width 0.1)
				(type default)
			)
			(layer "F.Fab")
		)
		(fp_line
			(start -0.12065 -0.2794)
			(end 0.12065 -0.2794)
			(stroke
				(width 0.1)
				(type default)
			)
			(layer "F.Fab")
		)
		(fp_line
			(start -0.12065 -0.305054)
			(end -0.12065 -0.2794)
			(stroke
				(width 0.1)
				(type default)
			)
			(layer "F.Fab")
		)
		(fp_line
			(start -0.67945 0.3048)
			(end -0.67945 -0.305054)
			(stroke
				(width 0.1)
				(type default)
			)
			(layer "F.Fab")
		)
		(fp_line
			(start -0.67945 -0.305054)
			(end -0.12065 -0.305054)
			(stroke
				(width 0.1)
				(type default)
			)
			(layer "F.Fab")
		)
		(pad "1" smd circle
			(at -0.40005 0 180)
			(size 0 0)
			(layers "F.Cu" "F.Mask" "F.Paste")
			(net "PWRGD_P12V_NIC4_CO")
		)
		(pad "2" smd circle
			(at 0.40005 0 180)
			(size 0 0)
			(layers "F.Cu" "F.Mask" "F.Paste")
			(net "PWRGD_P12V_NIC4_R")
		)
	)
	(footprint ""
		(layer "F.Cu")
		(at 423.120566 -70.307454 90)
		(property "Reference" "PC878"
			(at 0 0 90)
			(layer "F.SilkS")
			(hide yes)
			(effects
				(font
					(size 1.27 1.27)
				)
			)
		)
		(property "Value" ""
			(at 0 0 90)
			(layer "F.Fab")
			(effects
				(font
					(size 1.27 1.27)
				)
			)
		)
		(duplicate_pad_numbers_are_jumpers no)
		(fp_line
			(start 0.7874 -0.4064)
			(end 0.7874 0.4064)
			(stroke
				(width 0.1524)
				(type default)
			)
			(layer "F.SilkS")
		)
		(fp_line
			(start -0.7874 -0.4064)
			(end 0.7874 -0.4064)
			(stroke
				(width 0.1524)
				(type default)
			)
			(layer "F.SilkS")
		)
		(fp_line
			(start 0.7874 0.4064)
			(end -0.7874 0.4064)
			(stroke
				(width 0.1524)
				(type default)
			)
			(layer "F.SilkS")
		)
		(fp_line
			(start -0.7874 0.4064)
			(end -0.7874 -0.4064)
			(stroke
				(width 0.1524)
				(type default)
			)
			(layer "F.SilkS")
		)
		(fp_line
			(start -0.12065 -0.305054)
			(end -0.12065 -0.2794)
			(stroke
				(width 0.1)
				(type default)
			)
			(layer "F.Fab")
		)
		(fp_line
			(start -0.67945 -0.305054)
			(end -0.12065 -0.305054)
			(stroke
				(width 0.1)
				(type default)
			)
			(layer "F.Fab")
		)
		(fp_line
			(start 0.67945 -0.3048)
			(end 0.67945 0.3048)
			(stroke
				(width 0.1)
				(type default)
			)
			(layer "F.Fab")
		)
		(fp_line
			(start 0.12065 -0.3048)
			(end 0.67945 -0.3048)
			(stroke
				(width 0.1)
				(type default)
			)
			(layer "F.Fab")
		)
		(fp_line
			(start 0.12065 -0.2794)
			(end 0.12065 -0.3048)
			(stroke
				(width 0.1)
				(type default)
			)
			(layer "F.Fab")
		)
		(fp_line
			(start -0.12065 -0.2794)
			(end 0.12065 -0.2794)
			(stroke
				(width 0.1)
				(type default)
			)
			(layer "F.Fab")
		)
		(fp_line
			(start 0.120396 0.2794)
			(end -0.12065 0.2794)
			(stroke
				(width 0.1)
				(type default)
			)
			(layer "F.Fab")
		)
		(fp_line
			(start -0.12065 0.2794)
			(end -0.12065 0.3048)
			(stroke
				(width 0.1)
				(type default)
			)
			(layer "F.Fab")
		)
		(fp_line
			(start 0.67945 0.3048)
			(end 0.120396 0.3048)
			(stroke
				(width 0.1)
				(type default)
			)
			(layer "F.Fab")
		)
		(fp_line
			(start 0.120396 0.3048)
			(end 0.120396 0.2794)
			(stroke
				(width 0.1)
				(type default)
			)
			(layer "F.Fab")
		)
		(fp_line
			(start -0.12065 0.3048)
			(end -0.67945 0.3048)
			(stroke
				(width 0.1)
				(type default)
			)
			(layer "F.Fab")
		)
		(fp_line
			(start -0.67945 0.3048)
			(end -0.67945 -0.305054)
			(stroke
				(width 0.1)
				(type default)
			)
			(layer "F.Fab")
		)
		(pad "1" smd circle
			(at -0.40005 0 90)
			(size 0 0)
			(layers "F.Cu" "F.Mask" "F.Paste")
			(net "P12V_AUX")
		)
		(pad "2" smd circle
			(at 0.40005 0 90)
			(size 0 0)
			(layers "F.Cu" "F.Mask" "F.Paste")
			(net "GND")
		)
	)
	(footprint ""
		(layer "F.Cu")
		(at 72.273922 -72.766682 90)
		(property "Reference" "PR6909"
			(at 0 0 90)
			(layer "F.SilkS")
			(hide yes)
			(effects
				(font
					(size 1.27 1.27)
				)
			)
		)
		(property "Value" ""
			(at 0 0 90)
			(layer "F.Fab")
			(effects
				(font
					(size 1.27 1.27)
				)
			)
		)
		(duplicate_pad_numbers_are_jumpers no)
		(fp_line
			(start 0.7874 -0.4064)
			(end 0.7874 0.4064)
			(stroke
				(width 0.1524)
				(type default)
			)
			(layer "F.SilkS")
		)
		(fp_line
			(start -0.7874 -0.4064)
			(end 0.7874 -0.4064)
			(stroke
				(width 0.1524)
				(type default)
			)
			(layer "F.SilkS")
		)
		(fp_line
			(start 0.7874 0.4064)
			(end -0.7874 0.4064)
			(stroke
				(width 0.1524)
				(type default)
			)
			(layer "F.SilkS")
		)
		(fp_line
			(start -0.7874 0.4064)
			(end -0.7874 -0.4064)
			(stroke
				(width 0.1524)
				(type default)
			)
			(layer "F.SilkS")
		)
		(fp_line
			(start -0.12065 -0.305054)
			(end -0.12065 -0.2794)
			(stroke
				(width 0.1)
				(type default)
			)
			(layer "F.Fab")
		)
		(fp_line
			(start -0.67945 -0.305054)
			(end -0.12065 -0.305054)
			(stroke
				(width 0.1)
				(type default)
			)
			(layer "F.Fab")
		)
		(fp_line
			(start 0.67945 -0.3048)
			(end 0.67945 0.3048)
			(stroke
				(width 0.1)
				(type default)
			)
			(layer "F.Fab")
		)
		(fp_line
			(start 0.12065 -0.3048)
			(end 0.67945 -0.3048)
			(stroke
				(width 0.1)
				(type default)
			)
			(layer "F.Fab")
		)
		(fp_line
			(start 0.12065 -0.2794)
			(end 0.12065 -0.3048)
			(stroke
				(width 0.1)
				(type default)
			)
			(layer "F.Fab")
		)
		(fp_line
			(start -0.12065 -0.2794)
			(end 0.12065 -0.2794)
			(stroke
				(width 0.1)
				(type default)
			)
			(layer "F.Fab")
		)
		(fp_line
			(start 0.120396 0.2794)
			(end -0.12065 0.2794)
			(stroke
				(width 0.1)
				(type default)
			)
			(layer "F.Fab")
		)
		(fp_line
			(start -0.12065 0.2794)
			(end -0.12065 0.3048)
			(stroke
				(width 0.1)
				(type default)
			)
			(layer "F.Fab")
		)
		(fp_line
			(start 0.67945 0.3048)
			(end 0.120396 0.3048)
			(stroke
				(width 0.1)
				(type default)
			)
			(layer "F.Fab")
		)
		(fp_line
			(start 0.120396 0.3048)
			(end 0.120396 0.2794)
			(stroke
				(width 0.1)
				(type default)
			)
			(layer "F.Fab")
		)
		(fp_line
			(start -0.12065 0.3048)
			(end -0.67945 0.3048)
			(stroke
				(width 0.1)
				(type default)
			)
			(layer "F.Fab")
		)
		(fp_line
			(start -0.67945 0.3048)
			(end -0.67945 -0.305054)
			(stroke
				(width 0.1)
				(type default)
			)
			(layer "F.Fab")
		)
		(pad "1" smd circle
			(at -0.40005 0 90)
			(size 0 0)
			(layers "F.Cu" "F.Mask" "F.Paste")
			(net "P12V_SSD2_CO_MODE")
		)
		(pad "2" smd circle
			(at 0.40005 0 90)
			(size 0 0)
			(layers "F.Cu" "F.Mask" "F.Paste")
			(net "GND")
		)
	)
	(footprint ""
		(layer "F.Cu")
		(at 296.54119 -210.094068 -90)
		(property "Reference" "R3367"
			(at 0 0 270)
			(layer "F.SilkS")
			(hide yes)
			(effects
				(font
					(size 1.27 1.27)
				)
			)
		)
		(property "Value" ""
			(at 0 0 270)
			(layer "F.Fab")
			(effects
				(font
					(size 1.27 1.27)
				)
			)
		)
		(duplicate_pad_numbers_are_jumpers no)
		(fp_line
			(start -0.7874 0.4064)
			(end -0.7874 -0.4064)
			(stroke
				(width 0.1524)
				(type default)
			)
			(layer "F.SilkS")
		)
		(fp_line
			(start 0.7874 0.4064)
			(end -0.7874 0.4064)
			(stroke
				(width 0.1524)
				(type default)
			)
			(layer "F.SilkS")
		)
		(fp_line
			(start -0.7874 -0.4064)
			(end 0.7874 -0.4064)
			(stroke
				(width 0.1524)
				(type default)
			)
			(layer "F.SilkS")
		)
		(fp_line
			(start 0.7874 -0.4064)
			(end 0.7874 0.4064)
			(stroke
				(width 0.1524)
				(type default)
			)
			(layer "F.SilkS")
		)
		(fp_line
			(start -0.67945 0.3048)
			(end -0.67945 -0.305054)
			(stroke
				(width 0.1)
				(type default)
			)
			(layer "F.Fab")
		)
		(fp_line
			(start -0.12065 0.3048)
			(end -0.67945 0.3048)
			(stroke
				(width 0.1)
				(type default)
			)
			(layer "F.Fab")
		)
		(fp_line
			(start 0.120396 0.3048)
			(end 0.120396 0.2794)
			(stroke
				(width 0.1)
				(type default)
			)
			(layer "F.Fab")
		)
		(fp_line
			(start 0.67945 0.3048)
			(end 0.120396 0.3048)
			(stroke
				(width 0.1)
				(type default)
			)
			(layer "F.Fab")
		)
		(fp_line
			(start -0.12065 0.2794)
			(end -0.12065 0.3048)
			(stroke
				(width 0.1)
				(type default)
			)
			(layer "F.Fab")
		)
		(fp_line
			(start 0.120396 0.2794)
			(end -0.12065 0.2794)
			(stroke
				(width 0.1)
				(type default)
			)
			(layer "F.Fab")
		)
		(fp_line
			(start -0.12065 -0.2794)
			(end 0.12065 -0.2794)
			(stroke
				(width 0.1)
				(type default)
			)
			(layer "F.Fab")
		)
		(fp_line
			(start 0.12065 -0.2794)
			(end 0.12065 -0.3048)
			(stroke
				(width 0.1)
				(type default)
			)
			(layer "F.Fab")
		)
		(fp_line
			(start 0.12065 -0.3048)
			(end 0.67945 -0.3048)
			(stroke
				(width 0.1)
				(type default)
			)
			(layer "F.Fab")
		)
		(fp_line
			(start 0.67945 -0.3048)
			(end 0.67945 0.3048)
			(stroke
				(width 0.1)
				(type default)
			)
			(layer "F.Fab")
		)
		(fp_line
			(start -0.67945 -0.305054)
			(end -0.12065 -0.305054)
			(stroke
				(width 0.1)
				(type default)
			)
			(layer "F.Fab")
		)
		(fp_line
			(start -0.12065 -0.305054)
			(end -0.12065 -0.2794)
			(stroke
				(width 0.1)
				(type default)
			)
			(layer "F.Fab")
		)
		(pad "1" smd circle
			(at -0.40005 0 270)
			(size 0 0)
			(layers "F.Cu" "F.Mask" "F.Paste")
			(net "SPI_BIC1_MOSI_LS23_R")
		)
		(pad "2" smd circle
			(at 0.40005 0 270)
			(size 0 0)
			(layers "F.Cu" "F.Mask" "F.Paste")
			(net "SPI_BIC1_MOSI_LS23")
		)
	)
	(footprint ""
		(layer "F.Cu")
		(at 261.468362 -349.746824)
		(property "Reference" "U437"
			(at 0.670814 -2.57175 0)
			(unlocked yes)
			(layer "F.SilkS")
			(effects
				(font
					(size 0.7874 0.5842)
					(thickness 0.1524)
				)
				(justify left)
			)
		)
		(property "Value" ""
			(at 0 0 0)
			(layer "F.Fab")
			(effects
				(font
					(size 1.27 1.27)
				)
			)
		)
		(duplicate_pad_numbers_are_jumpers no)
		(fp_line
			(start -1.603248 -1.500124)
			(end 1.603248 -1.500124)
			(stroke
				(width 0.1524)
				(type default)
			)
			(layer "F.SilkS")
		)
		(fp_line
			(start -1.603248 1.500124)
			(end -1.603248 -1.500124)
			(stroke
				(width 0.1524)
				(type default)
			)
			(layer "F.SilkS")
		)
		(fp_line
			(start 1.603248 -1.500124)
			(end 1.603248 1.500124)
			(stroke
				(width 0.1524)
				(type default)
			)
			(layer "F.SilkS")
		)
		(fp_line
			(start 1.603248 1.500124)
			(end -1.603248 1.500124)
			(stroke
				(width 0.1524)
				(type default)
			)
			(layer "F.SilkS")
		)
		(fp_line
			(start -1.249934 -1.169924)
			(end -1.249934 -0.729996)
			(stroke
				(width 0.1)
				(type default)
			)
			(layer "F.Fab")
		)
		(fp_line
			(start -1.249934 -0.729996)
			(end -0.6985 -0.729996)
			(stroke
				(width 0.1)
				(type default)
			)
			(layer "F.Fab")
		)
		(fp_line
			(start -1.249934 0.729996)
			(end -1.249934 1.169924)
			(stroke
				(width 0.1)
				(type default)
			)
			(layer "F.Fab")
		)
		(fp_line
			(start -1.249934 1.169924)
			(end -0.700024 1.169924)
			(stroke
				(width 0.1)
				(type default)
			)
			(layer "F.Fab")
		)
		(fp_line
			(start -0.700024 -1.500124)
			(end -0.700024 -1.169924)
			(stroke
				(width 0.1)
				(type default)
			)
			(layer "F.Fab")
		)
		(fp_line
			(start -0.700024 -1.169924)
			(end -1.249934 -1.169924)
			(stroke
				(width 0.1)
				(type default)
			)
			(layer "F.Fab")
		)
		(fp_line
			(start -0.700024 1.169924)
			(end -0.700024 1.500124)
			(stroke
				(width 0.1)
				(type default)
			)
			(layer "F.Fab")
		)
		(fp_line
			(start -0.700024 1.500124)
			(end 0.700024 1.500124)
			(stroke
				(width 0.1)
				(type default)
			)
			(layer "F.Fab")
		)
		(fp_line
			(start -0.6985 -0.729996)
			(end -0.6985 0.729996)
			(stroke
				(width 0.1)
				(type default)
			)
			(layer "F.Fab")
		)
		(fp_line
			(start -0.6985 0.729996)
			(end -1.249934 0.729996)
			(stroke
				(width 0.1)
				(type default)
			)
			(layer "F.Fab")
		)
		(fp_line
			(start 0.700024 -1.500124)
			(end -0.700024 -1.500124)
			(stroke
				(width 0.1)
				(type default)
			)
			(layer "F.Fab")
		)
		(fp_line
			(start 0.700024 -0.219964)
			(end 0.700024 -1.500124)
			(stroke
				(width 0.1)
				(type default)
			)
			(layer "F.Fab")
		)
		(fp_line
			(start 0.700024 0.219964)
			(end 1.249934 0.219964)
			(stroke
				(width 0.1)
				(type default)
			)
			(layer "F.Fab")
		)
		(fp_line
			(start 0.700024 1.500124)
			(end 0.700024 0.219964)
			(stroke
				(width 0.1)
				(type default)
			)
			(layer "F.Fab")
		)
		(fp_line
			(start 1.249934 -0.219964)
			(end 0.700024 -0.219964)
			(stroke
				(width 0.1)
				(type default)
			)
			(layer "F.Fab")
		)
		(fp_line
			(start 1.249934 0.219964)
			(end 1.249934 -0.219964)
			(stroke
				(width 0.1)
				(type default)
			)
			(layer "F.Fab")
		)
		(fp_rect
			(start -0.700024 1.500124)
			(end 0.700024 -1.500124)
			(stroke
				(width 0)
				(type default)
			)
			(fill no)
			(layer "F.Fab")
		)
		(pad "D" smd rect
			(at 0.999998 0 270)
			(size 0.8128 0.9144)
			(layers "F.Cu" "F.Mask" "F.Paste")
			(net "A_HSC_LOW_DRAIN")
		)
		(pad "G" smd rect
			(at -0.999998 -0.94996 270)
			(size 0.8128 0.9144)
			(layers "F.Cu" "F.Mask" "F.Paste")
			(net "A_HSC_LOW_GATE")
		)
		(pad "S" smd rect
			(at -0.999998 0.94996 270)
			(size 0.8128 0.9144)
			(layers "F.Cu" "F.Mask" "F.Paste")
			(net "GND")
		)
	)
)
